# S9S_MB_2U (Grand Teton) — schematic netlist excerpt (pin names and nets, part order shuffled) for the footprints in the layout excerpt that follows; sources: Cadence DE-HDL packaged netlist, KiCad conversion of 03242023_DA0F0TMBIJ0_F0T_Motherboard_J_brd_V01_OCP.brd

R4181  Q_RES  33.2 1% CHIP  pkg 0402LF  page 170 : A = SMB_LM75_2_3V3AUX_SDA ; B = SMB_LM75_2_3V3AUX_SDA_R1
PR4271  Q_RES  0 5% CHIP  pkg 0402LF  page 282 : A = SW_PVNN_MAIN_CPU0_BST ; B = SW_PVNN_MAIN_CPU0_BST_R

(kicad_pcb
	(version 20260206)
	(generator "pcbnew")
	(generator_version "10.0")
	(general
		(thickness 1.6)
		(legacy_teardrops no)
	)
	(paper "A4")
	(title_block
		(title "03242023_DA0F0TMBIJ0_F0T_Motherboard_J_brd_V01_OCP.brd")
		(comment 1 "Grand Teton / footprints 3976-3977 of 6105")
	)
	(layers
		(0 "F.Cu" signal "TOP")
		(4 "In1.Cu" signal "GND")
		(6 "In2.Cu" signal "IN1")
		(8 "In3.Cu" signal "GND1")
		(10 "In4.Cu" signal "IN2")
		(12 "In5.Cu" signal "GND2")
		(14 "In6.Cu" signal "IN3")
		(16 "In7.Cu" signal "GND3")
		(18 "In8.Cu" signal "VCC")
		(20 "In9.Cu" signal "VCC1")
		(22 "In10.Cu" signal "GND4")
		(24 "In11.Cu" signal "IN4")
		(26 "In12.Cu" signal "GND5")
		(28 "In13.Cu" signal "IN5")
		(30 "In14.Cu" signal "GND6")
		(32 "In15.Cu" signal "IN6")
		(34 "In16.Cu" signal "GND7")
		(2 "B.Cu" signal "BOTTOM")
		(9 "F.Adhes" user "F.Adhesive")
		(11 "B.Adhes" user "B.Adhesive")
		(13 "F.Paste" user "Package Geometry/Pastemask Top")
		(15 "B.Paste" user "Package Geometry/Pastemask Bottom")
		(5 "F.SilkS" user "Ref Des/Silkscreen Top")
		(7 "B.SilkS" user "Ref Des/Silkscreen Bottom")
		(1 "F.Mask" user "Board Geometry/Soldermask Top")
		(3 "B.Mask" user "Board Geometry/Soldermask Bottom")
		(17 "Dwgs.User" user "User.Drawings")
		(19 "Cmts.User" user "User.Comments")
		(21 "Eco1.User" user "User.Eco1")
		(23 "Eco2.User" user "User.Eco2")
		(25 "Edge.Cuts" user "Board Geometry/Outline")
		(27 "Margin" user)
		(31 "F.CrtYd" user "Package Geometry/Place Bound Top")
		(29 "B.CrtYd" user "Package Geometry/Place Bound Bottom")
		(35 "F.Fab" user "Ref Des/Assembly Top")
		(33 "B.Fab" user "Ref Des/Assembly Bottom")
	)
	(footprint ""
		(layer "F.Cu")
		(at 105.21188 -424.779948 180)
		(property "Reference" "R4181"
			(at 0 0 180)
			(layer "F.SilkS")
			(hide yes)
			(effects
				(font
					(size 1.27 1.27)
				)
			)
		)
		(property "Value" ""
			(at 0 0 180)
			(layer "F.Fab")
			(effects
				(font
					(size 1.27 1.27)
				)
			)
		)
		(duplicate_pad_numbers_are_jumpers no)
		(fp_line
			(start 0.7874 0.4064)
			(end -0.7874 0.4064)
			(stroke
				(width 0.1524)
				(type default)
			)
			(layer "F.SilkS")
		)
		(fp_line
			(start 0.7874 -0.4064)
			(end 0.7874 0.4064)
			(stroke
				(width 0.1524)
				(type default)
			)
			(layer "F.SilkS")
		)
		(fp_line
			(start -0.7874 0.4064)
			(end -0.7874 -0.4064)
			(stroke
				(width 0.1524)
				(type default)
			)
			(layer "F.SilkS")
		)
		(fp_line
			(start -0.7874 -0.4064)
			(end 0.7874 -0.4064)
			(stroke
				(width 0.1524)
				(type default)
			)
			(layer "F.SilkS")
		)
		(fp_line
			(start 0.67945 0.3048)
			(end 0.120396 0.3048)
			(stroke
				(width 0.1)
				(type default)
			)
			(layer "F.Fab")
		)
		(fp_line
			(start 0.67945 -0.3048)
			(end 0.67945 0.3048)
			(stroke
				(width 0.1)
				(type default)
			)
			(layer "F.Fab")
		)
		(fp_line
			(start 0.12065 -0.2794)
			(end 0.12065 -0.3048)
			(stroke
				(width 0.1)
				(type default)
			)
			(layer "F.Fab")
		)
		(fp_line
			(start 0.12065 -0.3048)
			(end 0.67945 -0.3048)
			(stroke
				(width 0.1)
				(type default)
			)
			(layer "F.Fab")
		)
		(fp_line
			(start 0.120396 0.3048)
			(end 0.120396 0.2794)
			(stroke
				(width 0.1)
				(type default)
			)
			(layer "F.Fab")
		)
		(fp_line
			(start 0.120396 0.2794)
			(end -0.12065 0.2794)
			(stroke
				(width 0.1)
				(type default)
			)
			(layer "F.Fab")
		)
		(fp_line
			(start -0.12065 0.3048)
			(end -0.67945 0.3048)
			(stroke
				(width 0.1)
				(type default)
			)
			(layer "F.Fab")
		)
		(fp_line
			(start -0.12065 0.2794)
			(end -0.12065 0.3048)
			(stroke
				(width 0.1)
				(type default)
			)
			(layer "F.Fab")
		)
		(fp_line
			(start -0.12065 -0.2794)
			(end 0.12065 -0.2794)
			(stroke
				(width 0.1)
				(type default)
			)
			(layer "F.Fab")
		)
		(fp_line
			(start -0.12065 -0.305054)
			(end -0.12065 -0.2794)
			(stroke
				(width 0.1)
				(type default)
			)
			(layer "F.Fab")
		)
		(fp_line
			(start -0.67945 0.3048)
			(end -0.67945 -0.305054)
			(stroke
				(width 0.1)
				(type default)
			)
			(layer "F.Fab")
		)
		(fp_line
			(start -0.67945 -0.305054)
			(end -0.12065 -0.305054)
			(stroke
				(width 0.1)
				(type default)
			)
			(layer "F.Fab")
		)
		(pad "1" smd circle
			(at -0.40005 0 180)
			(size 0 0)
			(layers "F.Cu" "F.Mask" "F.Paste")
			(net "SMB_LM75_2_3V3AUX_SDA")
		)
		(pad "2" smd circle
			(at 0.40005 0 180)
			(size 0 0)
			(layers "F.Cu" "F.Mask" "F.Paste")
			(net "SMB_LM75_2_3V3AUX_SDA_R1")
		)
	)
	(footprint ""
		(layer "F.Cu")
		(at 435.43728 -179.390548 90)
		(property "Reference" "PR4271"
			(at 0 0 90)
			(layer "F.SilkS")
			(hide yes)
			(effects
				(font
					(size 1.27 1.27)
				)
			)
		)
		(property "Value" ""
			(at 0 0 90)
			(layer "F.Fab")
			(effects
				(font
					(size 1.27 1.27)
				)
			)
		)
		(duplicate_pad_numbers_are_jumpers no)
		(fp_line
			(start 0.7874 -0.4064)
			(end 0.7874 0.4064)
			(stroke
				(width 0.1524)
				(type default)
			)
			(layer "F.SilkS")
		)
		(fp_line
			(start -0.7874 -0.4064)
			(end 0.7874 -0.4064)
			(stroke
				(width 0.1524)
				(type default)
			)
			(layer "F.SilkS")
		)
		(fp_line
			(start 0.7874 0.4064)
			(end -0.7874 0.4064)
			(stroke
				(width 0.1524)
				(type default)
			)
			(layer "F.SilkS")
		)
		(fp_line
			(start -0.7874 0.4064)
			(end -0.7874 -0.4064)
			(stroke
				(width 0.1524)
				(type default)
			)
			(layer "F.SilkS")
		)
		(fp_line
			(start -0.12065 -0.305054)
			(end -0.12065 -0.2794)
			(stroke
				(width 0.1)
				(type default)
			)
			(layer "F.Fab")
		)
		(fp_line
			(start -0.67945 -0.305054)
			(end -0.12065 -0.305054)
			(stroke
				(width 0.1)
				(type default)
			)
			(layer "F.Fab")
		)
		(fp_line
			(start 0.67945 -0.3048)
			(end 0.67945 0.3048)
			(stroke
				(width 0.1)
				(type default)
			)
			(layer "F.Fab")
		)
		(fp_line
			(start 0.12065 -0.3048)
			(end 0.67945 -0.3048)
			(stroke
				(width 0.1)
				(type default)
			)
			(layer "F.Fab")
		)
		(fp_line
			(start 0.12065 -0.2794)
			(end 0.12065 -0.3048)
			(stroke
				(width 0.1)
				(type default)
			)
			(layer "F.Fab")
		)
		(fp_line
			(start -0.12065 -0.2794)
			(end 0.12065 -0.2794)
			(stroke
				(width 0.1)
				(type default)
			)
			(layer "F.Fab")
		)
		(fp_line
			(start 0.120396 0.2794)
			(end -0.12065 0.2794)
			(stroke
				(width 0.1)
				(type default)
			)
			(layer "F.Fab")
		)
		(fp_line
			(start -0.12065 0.2794)
			(end -0.12065 0.3048)
			(stroke
				(width 0.1)
				(type default)
			)
			(layer "F.Fab")
		)
		(fp_line
			(start 0.67945 0.3048)
			(end 0.120396 0.3048)
			(stroke
				(width 0.1)
				(type default)
			)
			(layer "F.Fab")
		)
		(fp_line
			(start 0.120396 0.3048)
			(end 0.120396 0.2794)
			(stroke
				(width 0.1)
				(type default)
			)
			(layer "F.Fab")
		)
		(fp_line
			(start -0.12065 0.3048)
			(end -0.67945 0.3048)
			(stroke
				(width 0.1)
				(type default)
			)
			(layer "F.Fab")
		)
		(fp_line
			(start -0.67945 0.3048)
			(end -0.67945 -0.305054)
			(stroke
				(width 0.1)
				(type default)
			)
			(layer "F.Fab")
		)
		(pad "1" smd circle
			(at -0.40005 0 90)
			(size 0 0)
			(layers "F.Cu" "F.Mask" "F.Paste")
			(net "SW_PVNN_MAIN_CPU0_BST")
		)
		(pad "2" smd circle
			(at 0.40005 0 90)
			(size 0 0)
			(layers "F.Cu" "F.Mask" "F.Paste")
			(net "SW_PVNN_MAIN_CPU0_BST_R")
		)
	)
)
